#ISCELL
  mstr_misc dns *
  *
#ISCELL
  mstr_symbols intel_corp_bpage *
  *
#ISCELL
  mstr_standard offpage *
  page249_i1
#ISCELL
  mstr_symbols gnd *
  page249_i10
#ISCELL
  mstr_symbols gnd *
  page249_i11
#ISCELL
  mstr_symbols gnd *
  page249_i14
#CELL
  w_hdl lmv331idckrg4-gp *
  page249_i15
#ISCELL
  mstr_symbols p3v3_stby *
  page249_i16
#CELL
  mstr_discrete res *
  page249_i2
#ISCELL
  mstr_symbols gnd *
  page249_i20
#ISCELL
  mstr_standard offpage *
  page249_i22
#ISCELL
  mstr_symbols p3v3_stby *
  page249_i24
#CELL
  mstr_discrete npn *
  page249_i29
#ISCELL
  mstr_symbols gnd *
  page249_i3
#CELL
  mstr_discrete fet_n *
  page249_i30
#CELL
  w_hdl 47kr2f-gp *
  page249_i31
#CELL
  mstr_discrete res *
  page249_i34
#ISCELL
  mstr_symbols p5v_stby *
  page249_i35
#CELL
  mstr_discrete res *
  page249_i36
#CELL
  dev_discrete cap_a *
  page249_i37
#CELL
  mstr_discrete res *
  page249_i48
#CELL
  mstr_discrete npn *
  page249_i49
#ISCELL
  mstr_standard offpage *
  page249_i5
#ISCELL
  mstr_symbols gnd *
  page249_i50
#ISCELL
  mstr_standard offpage *
  page249_i51
#CELL
  w_hdl sc1u16v3kx-2gp *
  page249_i52
#CELL
  mstr_discrete diode *
  page249_i55
#CELL
  mstr_discrete res *
  page249_i56
#CELL
  dev_discrete cap_a *
  page249_i57
#CELL
  mstr_discrete res *
  page249_i58
#ISCELL
  mstr_symbols gnd *
  page249_i6
#CELL
  mstr_discrete res *
  page249_i7
#CELL
  mstr_discrete res *
  page249_i8
#ISCELL
  mstr_symbols p3v3_stby *
  page249_i9
